(kicad_pcb
	(version 20260206)
	(generator "pcbnew")
	(generator_version "10.0")
	(general
		(thickness 1.6)
		(legacy_teardrops no)
	)
	(paper "A4")
	(title_block
		(title "04192023_DAF0TMB3IC0_F0TG_MB_C_brd_V02_OCP.brd")
		(comment 1 "Grand Teton / footprints 1301-1306 of 8354")
	)
	(layers
		(0 "F.Cu" signal "TOP")
		(4 "In1.Cu" signal "GND")
		(6 "In2.Cu" signal "IN1")
		(8 "In3.Cu" signal "GND1")
		(10 "In4.Cu" signal "IN2")
		(12 "In5.Cu" signal "GND2")
		(14 "In6.Cu" signal "IN3")
		(16 "In7.Cu" signal "GND3")
		(18 "In8.Cu" signal "VCC")
		(20 "In9.Cu" signal "VCC1")
		(22 "In10.Cu" signal "GND4")
		(24 "In11.Cu" signal "IN4")
		(26 "In12.Cu" signal "GND5")
		(28 "In13.Cu" signal "IN5")
		(30 "In14.Cu" signal "GND6")
		(32 "In15.Cu" signal "IN6")
		(34 "In16.Cu" signal "GND7")
		(2 "B.Cu" signal "BOTTOM")
		(9 "F.Adhes" user "F.Adhesive")
		(11 "B.Adhes" user "B.Adhesive")
		(13 "F.Paste" user "Package Geometry/Pastemask Top")
		(15 "B.Paste" user "Package Geometry/Pastemask Bottom")
		(5 "F.SilkS" user "Ref Des/Silkscreen Top")
		(7 "B.SilkS" user "Ref Des/Silkscreen Bottom")
		(1 "F.Mask" user "Board Geometry/Soldermask Top")
		(3 "B.Mask" user "Board Geometry/Soldermask Bottom")
		(17 "Dwgs.User" user "User.Drawings")
		(19 "Cmts.User" user "User.Comments")
		(21 "Eco1.User" user "User.Eco1")
		(23 "Eco2.User" user "User.Eco2")
		(25 "Edge.Cuts" user "Board Geometry/Outline")
		(27 "Margin" user)
		(31 "F.CrtYd" user "Package Geometry/Place Bound Top")
		(29 "B.CrtYd" user "Package Geometry/Place Bound Bottom")
		(35 "F.Fab" user "Ref Des/Assembly Top")
		(33 "B.Fab" user "Ref Des/Assembly Bottom")
	)
	(footprint ""
		(layer "F.Cu")
		(at 164.45103 -352.658934 90)
		(property "Reference" "PC644"
			(at 0 0 90)
			(layer "F.SilkS")
			(hide yes)
			(effects
				(font
					(size 1.27 1.27)
				)
			)
		)
		(property "Value" ""
			(at 0 0 90)
			(layer "F.Fab")
			(effects
				(font
					(size 1.27 1.27)
				)
			)
		)
		(duplicate_pad_numbers_are_jumpers no)
		(fp_line
			(start 0.7874 -0.4064)
			(end 0.7874 0.4064)
			(stroke
				(width 0.1524)
				(type default)
			)
			(layer "F.SilkS")
		)
		(fp_line
			(start -0.7874 -0.4064)
			(end 0.7874 -0.4064)
			(stroke
				(width 0.1524)
				(type default)
			)
			(layer "F.SilkS")
		)
		(fp_line
			(start 0.7874 0.4064)
			(end -0.7874 0.4064)
			(stroke
				(width 0.1524)
				(type default)
			)
			(layer "F.SilkS")
		)
		(fp_line
			(start -0.7874 0.4064)
			(end -0.7874 -0.4064)
			(stroke
				(width 0.1524)
				(type default)
			)
			(layer "F.SilkS")
		)
		(fp_line
			(start -0.12065 -0.305054)
			(end -0.12065 -0.2794)
			(stroke
				(width 0.1)
				(type default)
			)
			(layer "F.Fab")
		)
		(fp_line
			(start -0.67945 -0.305054)
			(end -0.12065 -0.305054)
			(stroke
				(width 0.1)
				(type default)
			)
			(layer "F.Fab")
		)
		(fp_line
			(start 0.67945 -0.3048)
			(end 0.67945 0.3048)
			(stroke
				(width 0.1)
				(type default)
			)
			(layer "F.Fab")
		)
		(fp_line
			(start 0.12065 -0.3048)
			(end 0.67945 -0.3048)
			(stroke
				(width 0.1)
				(type default)
			)
			(layer "F.Fab")
		)
		(fp_line
			(start 0.12065 -0.2794)
			(end 0.12065 -0.3048)
			(stroke
				(width 0.1)
				(type default)
			)
			(layer "F.Fab")
		)
		(fp_line
			(start -0.12065 -0.2794)
			(end 0.12065 -0.2794)
			(stroke
				(width 0.1)
				(type default)
			)
			(layer "F.Fab")
		)
		(fp_line
			(start 0.120396 0.2794)
			(end -0.12065 0.2794)
			(stroke
				(width 0.1)
				(type default)
			)
			(layer "F.Fab")
		)
		(fp_line
			(start -0.12065 0.2794)
			(end -0.12065 0.3048)
			(stroke
				(width 0.1)
				(type default)
			)
			(layer "F.Fab")
		)
		(fp_line
			(start 0.67945 0.3048)
			(end 0.120396 0.3048)
			(stroke
				(width 0.1)
				(type default)
			)
			(layer "F.Fab")
		)
		(fp_line
			(start 0.120396 0.3048)
			(end 0.120396 0.2794)
			(stroke
				(width 0.1)
				(type default)
			)
			(layer "F.Fab")
		)
		(fp_line
			(start -0.12065 0.3048)
			(end -0.67945 0.3048)
			(stroke
				(width 0.1)
				(type default)
			)
			(layer "F.Fab")
		)
		(fp_line
			(start -0.67945 0.3048)
			(end -0.67945 -0.305054)
			(stroke
				(width 0.1)
				(type default)
			)
			(layer "F.Fab")
		)
		(pad "1" smd circle
			(at -0.40005 0 90)
			(size 0 0)
			(layers "F.Cu" "F.Mask" "F.Paste")
			(net "PVDD11_S3_P1_VCCS")
		)
		(pad "2" smd circle
			(at 0.40005 0 90)
			(size 0 0)
			(layers "F.Cu" "F.Mask" "F.Paste")
			(net "GND")
		)
	)
	(footprint ""
		(layer "F.Cu")
		(at 296.681906 -349.381572 90)
		(property "Reference" "PC143"
			(at 0 0 90)
			(layer "F.SilkS")
			(hide yes)
			(effects
				(font
					(size 1.27 1.27)
				)
			)
		)
		(property "Value" ""
			(at 0 0 90)
			(layer "F.Fab")
			(effects
				(font
					(size 1.27 1.27)
				)
			)
		)
		(duplicate_pad_numbers_are_jumpers no)
		(fp_line
			(start 0.7874 -0.4064)
			(end 0.7874 0.4064)
			(stroke
				(width 0.1524)
				(type default)
			)
			(layer "F.SilkS")
		)
		(fp_line
			(start -0.7874 -0.4064)
			(end 0.7874 -0.4064)
			(stroke
				(width 0.1524)
				(type default)
			)
			(layer "F.SilkS")
		)
		(fp_line
			(start 0.7874 0.4064)
			(end 0.401828 0.4064)
			(stroke
				(width 0.1524)
				(type default)
			)
			(layer "F.SilkS")
		)
		(fp_line
			(start -0.207772 0.4064)
			(end -0.7874 0.4064)
			(stroke
				(width 0.1524)
				(type default)
			)
			(layer "F.SilkS")
		)
		(fp_line
			(start -0.7874 0.4064)
			(end -0.7874 -0.4064)
			(stroke
				(width 0.1524)
				(type default)
			)
			(layer "F.SilkS")
		)
		(fp_line
			(start -0.12065 -0.305054)
			(end -0.12065 -0.2794)
			(stroke
				(width 0.1)
				(type default)
			)
			(layer "F.Fab")
		)
		(fp_line
			(start -0.67945 -0.305054)
			(end -0.12065 -0.305054)
			(stroke
				(width 0.1)
				(type default)
			)
			(layer "F.Fab")
		)
		(fp_line
			(start 0.67945 -0.3048)
			(end 0.67945 0.3048)
			(stroke
				(width 0.1)
				(type default)
			)
			(layer "F.Fab")
		)
		(fp_line
			(start 0.12065 -0.3048)
			(end 0.67945 -0.3048)
			(stroke
				(width 0.1)
				(type default)
			)
			(layer "F.Fab")
		)
		(fp_line
			(start 0.12065 -0.2794)
			(end 0.12065 -0.3048)
			(stroke
				(width 0.1)
				(type default)
			)
			(layer "F.Fab")
		)
		(fp_line
			(start -0.12065 -0.2794)
			(end 0.12065 -0.2794)
			(stroke
				(width 0.1)
				(type default)
			)
			(layer "F.Fab")
		)
		(fp_line
			(start 0.120396 0.2794)
			(end -0.12065 0.2794)
			(stroke
				(width 0.1)
				(type default)
			)
			(layer "F.Fab")
		)
		(fp_line
			(start -0.12065 0.2794)
			(end -0.12065 0.3048)
			(stroke
				(width 0.1)
				(type default)
			)
			(layer "F.Fab")
		)
		(fp_line
			(start 0.67945 0.3048)
			(end 0.120396 0.3048)
			(stroke
				(width 0.1)
				(type default)
			)
			(layer "F.Fab")
		)
		(fp_line
			(start 0.120396 0.3048)
			(end 0.120396 0.2794)
			(stroke
				(width 0.1)
				(type default)
			)
			(layer "F.Fab")
		)
		(fp_line
			(start -0.12065 0.3048)
			(end -0.67945 0.3048)
			(stroke
				(width 0.1)
				(type default)
			)
			(layer "F.Fab")
		)
		(fp_line
			(start -0.67945 0.3048)
			(end -0.67945 -0.305054)
			(stroke
				(width 0.1)
				(type default)
			)
			(layer "F.Fab")
		)
		(pad "1" smd circle
			(at -0.40005 0 90)
			(size 0 0)
			(layers "F.Cu" "F.Mask" "F.Paste")
			(net "PVDDIO_P0_VCC1")
		)
		(pad "2" smd circle
			(at 0.40005 0 90)
			(size 0 0)
			(layers "F.Cu" "F.Mask" "F.Paste")
			(net "GND")
		)
	)
	(footprint ""
		(layer "F.Cu")
		(at 116.109496 -375.49963 -90)
		(property "Reference" "C1538"
			(at 0 0 270)
			(layer "F.SilkS")
			(hide yes)
			(effects
				(font
					(size 1.27 1.27)
				)
			)
		)
		(property "Value" ""
			(at 0 0 270)
			(layer "F.Fab")
			(effects
				(font
					(size 1.27 1.27)
				)
			)
		)
		(duplicate_pad_numbers_are_jumpers no)
		(fp_line
			(start -0.299974 0.150114)
			(end -0.299974 -0.150114)
			(stroke
				(width 0.1)
				(type default)
			)
			(layer "F.Fab")
		)
		(fp_line
			(start 0.299974 0.150114)
			(end -0.299974 0.150114)
			(stroke
				(width 0.1)
				(type default)
			)
			(layer "F.Fab")
		)
		(fp_line
			(start -0.299974 -0.150114)
			(end 0.299974 -0.150114)
			(stroke
				(width 0.1)
				(type default)
			)
			(layer "F.Fab")
		)
		(fp_line
			(start 0.299974 -0.150114)
			(end 0.299974 0.150114)
			(stroke
				(width 0.1)
				(type default)
			)
			(layer "F.Fab")
		)
		(pad "1" smd rect
			(at -0.2667 0 270)
			(size 0.3048 0.381)
			(layers "F.Cu" "F.Mask" "F.Paste")
			(net "P5E_CPU1_P3_TX_C_DN<4>")
		)
		(pad "2" smd rect
			(at 0.2667 0 270)
			(size 0.3048 0.381)
			(layers "F.Cu" "F.Mask" "F.Paste")
			(net "P5E_CPU1_P3_TX_DN<4>")
		)
	)
	(footprint ""
		(layer "F.Cu")
		(at 17.812258 -427.580298 90)
		(property "Reference" "R6170"
			(at 0 0 90)
			(layer "F.SilkS")
			(hide yes)
			(effects
				(font
					(size 1.27 1.27)
				)
			)
		)
		(property "Value" ""
			(at 0 0 90)
			(layer "F.Fab")
			(effects
				(font
					(size 1.27 1.27)
				)
			)
		)
		(duplicate_pad_numbers_are_jumpers no)
		(fp_line
			(start 0.7874 -0.4064)
			(end 0.7874 0.4064)
			(stroke
				(width 0.1524)
				(type default)
			)
			(layer "F.SilkS")
		)
		(fp_line
			(start -0.7874 -0.4064)
			(end 0.7874 -0.4064)
			(stroke
				(width 0.1524)
				(type default)
			)
			(layer "F.SilkS")
		)
		(fp_line
			(start 0.7874 0.4064)
			(end -0.7874 0.4064)
			(stroke
				(width 0.1524)
				(type default)
			)
			(layer "F.SilkS")
		)
		(fp_line
			(start -0.7874 0.4064)
			(end -0.7874 -0.4064)
			(stroke
				(width 0.1524)
				(type default)
			)
			(layer "F.SilkS")
		)
		(fp_line
			(start -0.12065 -0.305054)
			(end -0.12065 -0.2794)
			(stroke
				(width 0.1)
				(type default)
			)
			(layer "F.Fab")
		)
		(fp_line
			(start -0.67945 -0.305054)
			(end -0.12065 -0.305054)
			(stroke
				(width 0.1)
				(type default)
			)
			(layer "F.Fab")
		)
		(fp_line
			(start 0.67945 -0.3048)
			(end 0.67945 0.3048)
			(stroke
				(width 0.1)
				(type default)
			)
			(layer "F.Fab")
		)
		(fp_line
			(start 0.12065 -0.3048)
			(end 0.67945 -0.3048)
			(stroke
				(width 0.1)
				(type default)
			)
			(layer "F.Fab")
		)
		(fp_line
			(start 0.12065 -0.2794)
			(end 0.12065 -0.3048)
			(stroke
				(width 0.1)
				(type default)
			)
			(layer "F.Fab")
		)
		(fp_line
			(start -0.12065 -0.2794)
			(end 0.12065 -0.2794)
			(stroke
				(width 0.1)
				(type default)
			)
			(layer "F.Fab")
		)
		(fp_line
			(start 0.120396 0.2794)
			(end -0.12065 0.2794)
			(stroke
				(width 0.1)
				(type default)
			)
			(layer "F.Fab")
		)
		(fp_line
			(start -0.12065 0.2794)
			(end -0.12065 0.3048)
			(stroke
				(width 0.1)
				(type default)
			)
			(layer "F.Fab")
		)
		(fp_line
			(start 0.67945 0.3048)
			(end 0.120396 0.3048)
			(stroke
				(width 0.1)
				(type default)
			)
			(layer "F.Fab")
		)
		(fp_line
			(start 0.120396 0.3048)
			(end 0.120396 0.2794)
			(stroke
				(width 0.1)
				(type default)
			)
			(layer "F.Fab")
		)
		(fp_line
			(start -0.12065 0.3048)
			(end -0.67945 0.3048)
			(stroke
				(width 0.1)
				(type default)
			)
			(layer "F.Fab")
		)
		(fp_line
			(start -0.67945 0.3048)
			(end -0.67945 -0.305054)
			(stroke
				(width 0.1)
				(type default)
			)
			(layer "F.Fab")
		)
		(pad "1" smd circle
			(at -0.40005 0 90)
			(size 0 0)
			(layers "F.Cu" "F.Mask" "F.Paste")
			(net "FM_P2E_BUF2_VODA_DB")
		)
		(pad "2" smd circle
			(at 0.40005 0 90)
			(size 0 0)
			(layers "F.Cu" "F.Mask" "F.Paste")
			(net "GND")
		)
	)
	(footprint ""
		(layer "F.Cu")
		(at 329.917044 -151.14397 -90)
		(property "Reference" "PC215"
			(at 0 0 270)
			(layer "F.SilkS")
			(hide yes)
			(effects
				(font
					(size 1.27 1.27)
				)
			)
		)
		(property "Value" ""
			(at 0 0 270)
			(layer "F.Fab")
			(effects
				(font
					(size 1.27 1.27)
				)
			)
		)
		(duplicate_pad_numbers_are_jumpers no)
		(fp_line
			(start -0.7874 0.4064)
			(end -0.7874 -0.4064)
			(stroke
				(width 0.1524)
				(type default)
			)
			(layer "F.SilkS")
		)
		(fp_line
			(start 0.7874 0.4064)
			(end -0.7874 0.4064)
			(stroke
				(width 0.1524)
				(type default)
			)
			(layer "F.SilkS")
		)
		(fp_line
			(start -0.7874 -0.4064)
			(end 0.7874 -0.4064)
			(stroke
				(width 0.1524)
				(type default)
			)
			(layer "F.SilkS")
		)
		(fp_line
			(start 0.7874 -0.4064)
			(end 0.7874 0.4064)
			(stroke
				(width 0.1524)
				(type default)
			)
			(layer "F.SilkS")
		)
		(fp_line
			(start -0.67945 0.3048)
			(end -0.67945 -0.305054)
			(stroke
				(width 0.1)
				(type default)
			)
			(layer "F.Fab")
		)
		(fp_line
			(start -0.12065 0.3048)
			(end -0.67945 0.3048)
			(stroke
				(width 0.1)
				(type default)
			)
			(layer "F.Fab")
		)
		(fp_line
			(start 0.120396 0.3048)
			(end 0.120396 0.2794)
			(stroke
				(width 0.1)
				(type default)
			)
			(layer "F.Fab")
		)
		(fp_line
			(start 0.67945 0.3048)
			(end 0.120396 0.3048)
			(stroke
				(width 0.1)
				(type default)
			)
			(layer "F.Fab")
		)
		(fp_line
			(start -0.12065 0.2794)
			(end -0.12065 0.3048)
			(stroke
				(width 0.1)
				(type default)
			)
			(layer "F.Fab")
		)
		(fp_line
			(start 0.120396 0.2794)
			(end -0.12065 0.2794)
			(stroke
				(width 0.1)
				(type default)
			)
			(layer "F.Fab")
		)
		(fp_line
			(start -0.12065 -0.2794)
			(end 0.12065 -0.2794)
			(stroke
				(width 0.1)
				(type default)
			)
			(layer "F.Fab")
		)
		(fp_line
			(start 0.12065 -0.2794)
			(end 0.12065 -0.3048)
			(stroke
				(width 0.1)
				(type default)
			)
			(layer "F.Fab")
		)
		(fp_line
			(start 0.12065 -0.3048)
			(end 0.67945 -0.3048)
			(stroke
				(width 0.1)
				(type default)
			)
			(layer "F.Fab")
		)
		(fp_line
			(start 0.67945 -0.3048)
			(end 0.67945 0.3048)
			(stroke
				(width 0.1)
				(type default)
			)
			(layer "F.Fab")
		)
		(fp_line
			(start -0.67945 -0.305054)
			(end -0.12065 -0.305054)
			(stroke
				(width 0.1)
				(type default)
			)
			(layer "F.Fab")
		)
		(fp_line
			(start -0.12065 -0.305054)
			(end -0.12065 -0.2794)
			(stroke
				(width 0.1)
				(type default)
			)
			(layer "F.Fab")
		)
		(pad "1" smd circle
			(at -0.40005 0 270)
			(size 0 0)
			(layers "F.Cu" "F.Mask" "F.Paste")
			(net "PVDD18_S5_P0")
		)
		(pad "2" smd circle
			(at 0.40005 0 270)
			(size 0 0)
			(layers "F.Cu" "F.Mask" "F.Paste")
			(net "GND")
		)
	)
	(footprint ""
		(layer "F.Cu")
		(at 118.618 -440.309 180)
		(property "Reference" "R3491"
			(at 0 0 180)
			(layer "F.SilkS")
			(hide yes)
			(effects
				(font
					(size 1.27 1.27)
				)
			)
		)
		(property "Value" ""
			(at 0 0 180)
			(layer "F.Fab")
			(effects
				(font
					(size 1.27 1.27)
				)
			)
		)
		(duplicate_pad_numbers_are_jumpers no)
		(fp_line
			(start 0.7874 0.4064)
			(end -0.7874 0.4064)
			(stroke
				(width 0.1524)
				(type default)
			)
			(layer "F.SilkS")
		)
		(fp_line
			(start 0.7874 -0.4064)
			(end 0.7874 0.4064)
			(stroke
				(width 0.1524)
				(type default)
			)
			(layer "F.SilkS")
		)
		(fp_line
			(start -0.7874 0.4064)
			(end -0.7874 -0.4064)
			(stroke
				(width 0.1524)
				(type default)
			)
			(layer "F.SilkS")
		)
		(fp_line
			(start -0.7874 -0.4064)
			(end 0.7874 -0.4064)
			(stroke
				(width 0.1524)
				(type default)
			)
			(layer "F.SilkS")
		)
		(fp_line
			(start 0.67945 0.3048)
			(end 0.120396 0.3048)
			(stroke
				(width 0.1)
				(type default)
			)
			(layer "F.Fab")
		)
		(fp_line
			(start 0.67945 -0.3048)
			(end 0.67945 0.3048)
			(stroke
				(width 0.1)
				(type default)
			)
			(layer "F.Fab")
		)
		(fp_line
			(start 0.12065 -0.2794)
			(end 0.12065 -0.3048)
			(stroke
				(width 0.1)
				(type default)
			)
			(layer "F.Fab")
		)
		(fp_line
			(start 0.12065 -0.3048)
			(end 0.67945 -0.3048)
			(stroke
				(width 0.1)
				(type default)
			)
			(layer "F.Fab")
		)
		(fp_line
			(start 0.120396 0.3048)
			(end 0.120396 0.2794)
			(stroke
				(width 0.1)
				(type default)
			)
			(layer "F.Fab")
		)
		(fp_line
			(start 0.120396 0.2794)
			(end -0.12065 0.2794)
			(stroke
				(width 0.1)
				(type default)
			)
			(layer "F.Fab")
		)
		(fp_line
			(start -0.12065 0.3048)
			(end -0.67945 0.3048)
			(stroke
				(width 0.1)
				(type default)
			)
			(layer "F.Fab")
		)
		(fp_line
			(start -0.12065 0.2794)
			(end -0.12065 0.3048)
			(stroke
				(width 0.1)
				(type default)
			)
			(layer "F.Fab")
		)
		(fp_line
			(start -0.12065 -0.2794)
			(end 0.12065 -0.2794)
			(stroke
				(width 0.1)
				(type default)
			)
			(layer "F.Fab")
		)
		(fp_line
			(start -0.12065 -0.305054)
			(end -0.12065 -0.2794)
			(stroke
				(width 0.1)
				(type default)
			)
			(layer "F.Fab")
		)
		(fp_line
			(start -0.67945 0.3048)
			(end -0.67945 -0.305054)
			(stroke
				(width 0.1)
				(type default)
			)
			(layer "F.Fab")
		)
		(fp_line
			(start -0.67945 -0.305054)
			(end -0.12065 -0.305054)
			(stroke
				(width 0.1)
				(type default)
			)
			(layer "F.Fab")
		)
		(pad "1" smd circle
			(at -0.40005 0 180)
			(size 0 0)
			(layers "F.Cu" "F.Mask" "F.Paste")
			(net "GPU_FPGA_EROT_RECOV_N")
		)
		(pad "2" smd circle
			(at 0.40005 0 180)
			(size 0 0)
			(layers "F.Cu" "F.Mask" "F.Paste")
			(net "GND")
		)
	)
)
